# S9S_MB_2U (Grand Teton) — schematic netlist excerpt (pin names and nets, part order shuffled) for the footprints in the layout excerpt that follows; sources: Cadence DE-HDL packaged netlist, KiCad conversion of 03242023_DA0F0TMBIJ0_F0T_Motherboard_J_brd_V01_OCP.brd

R4160  Q_RES  54.9K 1% EMPTY  pkg 0402LF  page 145 : A = P3V3_AUX ; B = GPU_3V3IO_RSVD4

(kicad_pcb
	(version 20260206)
	(generator "pcbnew")
	(generator_version "10.0")
	(general
		(thickness 1.6)
		(legacy_teardrops no)
	)
	(paper "A4")
	(title_block
		(title "03242023_DA0F0TMBIJ0_F0T_Motherboard_J_brd_V01_OCP.brd")
		(comment 1 "Grand Teton / footprints 2049-2049 of 6105")
	)
	(layers
		(0 "F.Cu" signal "TOP")
		(4 "In1.Cu" signal "GND")
		(6 "In2.Cu" signal "IN1")
		(8 "In3.Cu" signal "GND1")
		(10 "In4.Cu" signal "IN2")
		(12 "In5.Cu" signal "GND2")
		(14 "In6.Cu" signal "IN3")
		(16 "In7.Cu" signal "GND3")
		(18 "In8.Cu" signal "VCC")
		(20 "In9.Cu" signal "VCC1")
		(22 "In10.Cu" signal "GND4")
		(24 "In11.Cu" signal "IN4")
		(26 "In12.Cu" signal "GND5")
		(28 "In13.Cu" signal "IN5")
		(30 "In14.Cu" signal "GND6")
		(32 "In15.Cu" signal "IN6")
		(34 "In16.Cu" signal "GND7")
		(2 "B.Cu" signal "BOTTOM")
		(9 "F.Adhes" user "F.Adhesive")
		(11 "B.Adhes" user "B.Adhesive")
		(13 "F.Paste" user "Package Geometry/Pastemask Top")
		(15 "B.Paste" user "Package Geometry/Pastemask Bottom")
		(5 "F.SilkS" user "Ref Des/Silkscreen Top")
		(7 "B.SilkS" user "Ref Des/Silkscreen Bottom")
		(1 "F.Mask" user "Board Geometry/Soldermask Top")
		(3 "B.Mask" user "Board Geometry/Soldermask Bottom")
		(17 "Dwgs.User" user "User.Drawings")
		(19 "Cmts.User" user "User.Comments")
		(21 "Eco1.User" user "User.Eco1")
		(23 "Eco2.User" user "User.Eco2")
		(25 "Edge.Cuts" user "Board Geometry/Outline")
		(27 "Margin" user)
		(31 "F.CrtYd" user "Package Geometry/Place Bound Top")
		(29 "B.CrtYd" user "Package Geometry/Place Bound Bottom")
		(35 "F.Fab" user "Ref Des/Assembly Top")
		(33 "B.Fab" user "Ref Des/Assembly Bottom")
	)
	(footprint ""
		(layer "F.Cu")
		(at 360.482642 -393.28725)
		(property "Reference" "R4160"
			(at 0 0 0)
			(layer "F.SilkS")
			(hide yes)
			(effects
				(font
					(size 1.27 1.27)
				)
			)
		)
		(property "Value" ""
			(at 0 0 0)
			(layer "F.Fab")
			(effects
				(font
					(size 1.27 1.27)
				)
			)
		)
		(duplicate_pad_numbers_are_jumpers no)
		(fp_line
			(start -0.7874 -0.4064)
			(end 0.7874 -0.4064)
			(stroke
				(width 0.1524)
				(type default)
			)
			(layer "F.SilkS")
		)
		(fp_line
			(start -0.7874 0.4064)
			(end -0.7874 -0.4064)
			(stroke
				(width 0.1524)
				(type default)
			)
			(layer "F.SilkS")
		)
		(fp_line
			(start 0.7874 -0.4064)
			(end 0.7874 0.4064)
			(stroke
				(width 0.1524)
				(type default)
			)
			(layer "F.SilkS")
		)
		(fp_line
			(start 0.7874 0.4064)
			(end -0.7874 0.4064)
			(stroke
				(width 0.1524)
				(type default)
			)
			(layer "F.SilkS")
		)
		(fp_line
			(start -0.67945 -0.305054)
			(end -0.12065 -0.305054)
			(stroke
				(width 0.1)
				(type default)
			)
			(layer "F.Fab")
		)
		(fp_line
			(start -0.67945 0.3048)
			(end -0.67945 -0.305054)
			(stroke
				(width 0.1)
				(type default)
			)
			(layer "F.Fab")
		)
		(fp_line
			(start -0.12065 -0.305054)
			(end -0.12065 -0.2794)
			(stroke
				(width 0.1)
				(type default)
			)
			(layer "F.Fab")
		)
		(fp_line
			(start -0.12065 -0.2794)
			(end 0.12065 -0.2794)
			(stroke
				(width 0.1)
				(type default)
			)
			(layer "F.Fab")
		)
		(fp_line
			(start -0.12065 0.2794)
			(end -0.12065 0.3048)
			(stroke
				(width 0.1)
				(type default)
			)
			(layer "F.Fab")
		)
		(fp_line
			(start -0.12065 0.3048)
			(end -0.67945 0.3048)
			(stroke
				(width 0.1)
				(type default)
			)
			(layer "F.Fab")
		)
		(fp_line
			(start 0.120396 0.2794)
			(end -0.12065 0.2794)
			(stroke
				(width 0.1)
				(type default)
			)
			(layer "F.Fab")
		)
		(fp_line
			(start 0.120396 0.3048)
			(end 0.120396 0.2794)
			(stroke
				(width 0.1)
				(type default)
			)
			(layer "F.Fab")
		)
		(fp_line
			(start 0.12065 -0.3048)
			(end 0.67945 -0.3048)
			(stroke
				(width 0.1)
				(type default)
			)
			(layer "F.Fab")
		)
		(fp_line
			(start 0.12065 -0.2794)
			(end 0.12065 -0.3048)
			(stroke
				(width 0.1)
				(type default)
			)
			(layer "F.Fab")
		)
		(fp_line
			(start 0.67945 -0.3048)
			(end 0.67945 0.3048)
			(stroke
				(width 0.1)
				(type default)
			)
			(layer "F.Fab")
		)
		(fp_line
			(start 0.67945 0.3048)
			(end 0.120396 0.3048)
			(stroke
				(width 0.1)
				(type default)
			)
			(layer "F.Fab")
		)
		(pad "1" smd circle
			(at -0.40005 0)
			(size 0 0)
			(layers "F.Cu" "F.Mask" "F.Paste")
			(net "P3V3_AUX")
		)
		(pad "2" smd circle
			(at 0.40005 0)
			(size 0 0)
			(layers "F.Cu" "F.Mask" "F.Paste")
			(net "GPU_3V3IO_RSVD4")
		)
	)
)
